(kicad_pcb
	(version 20260206)
	(generator "pcbnew")
	(generator_version "10.0")
	(general
		(thickness 1.6)
		(legacy_teardrops no)
	)
	(paper "A4")
	(title_block
		(title "03242023_DA0F0TMBIJ0_F0T_Motherboard_J_brd_V01_OCP.brd")
		(comment 1 "Grand Teton / footprints 340-346 of 6105")
	)
	(layers
		(0 "F.Cu" signal "TOP")
		(4 "In1.Cu" signal "GND")
		(6 "In2.Cu" signal "IN1")
		(8 "In3.Cu" signal "GND1")
		(10 "In4.Cu" signal "IN2")
		(12 "In5.Cu" signal "GND2")
		(14 "In6.Cu" signal "IN3")
		(16 "In7.Cu" signal "GND3")
		(18 "In8.Cu" signal "VCC")
		(20 "In9.Cu" signal "VCC1")
		(22 "In10.Cu" signal "GND4")
		(24 "In11.Cu" signal "IN4")
		(26 "In12.Cu" signal "GND5")
		(28 "In13.Cu" signal "IN5")
		(30 "In14.Cu" signal "GND6")
		(32 "In15.Cu" signal "IN6")
		(34 "In16.Cu" signal "GND7")
		(2 "B.Cu" signal "BOTTOM")
		(9 "F.Adhes" user "F.Adhesive")
		(11 "B.Adhes" user "B.Adhesive")
		(13 "F.Paste" user "Package Geometry/Pastemask Top")
		(15 "B.Paste" user "Package Geometry/Pastemask Bottom")
		(5 "F.SilkS" user "Ref Des/Silkscreen Top")
		(7 "B.SilkS" user "Ref Des/Silkscreen Bottom")
		(1 "F.Mask" user "Board Geometry/Soldermask Top")
		(3 "B.Mask" user "Board Geometry/Soldermask Bottom")
		(17 "Dwgs.User" user "User.Drawings")
		(19 "Cmts.User" user "User.Comments")
		(21 "Eco1.User" user "User.Eco1")
		(23 "Eco2.User" user "User.Eco2")
		(25 "Edge.Cuts" user "Board Geometry/Outline")
		(27 "Margin" user)
		(31 "F.CrtYd" user "Package Geometry/Place Bound Top")
		(29 "B.CrtYd" user "Package Geometry/Place Bound Bottom")
		(35 "F.Fab" user "Ref Des/Assembly Top")
		(33 "B.Fab" user "Ref Des/Assembly Bottom")
	)
	(footprint ""
		(layer "F.Cu")
		(at 220.363034 -75.02779 -90)
		(property "Reference" "PR3967"
			(at 0 0 270)
			(layer "F.SilkS")
			(hide yes)
			(effects
				(font
					(size 1.27 1.27)
				)
			)
		)
		(property "Value" ""
			(at 0 0 270)
			(layer "F.Fab")
			(effects
				(font
					(size 1.27 1.27)
				)
			)
		)
		(duplicate_pad_numbers_are_jumpers no)
		(fp_line
			(start -0.7874 0.4064)
			(end -0.7874 -0.4064)
			(stroke
				(width 0.1524)
				(type default)
			)
			(layer "F.SilkS")
		)
		(fp_line
			(start 0.7874 0.4064)
			(end -0.7874 0.4064)
			(stroke
				(width 0.1524)
				(type default)
			)
			(layer "F.SilkS")
		)
		(fp_line
			(start -0.7874 -0.4064)
			(end 0.7874 -0.4064)
			(stroke
				(width 0.1524)
				(type default)
			)
			(layer "F.SilkS")
		)
		(fp_line
			(start 0.7874 -0.4064)
			(end 0.7874 0.4064)
			(stroke
				(width 0.1524)
				(type default)
			)
			(layer "F.SilkS")
		)
		(fp_line
			(start -0.67945 0.3048)
			(end -0.67945 -0.305054)
			(stroke
				(width 0.1)
				(type default)
			)
			(layer "F.Fab")
		)
		(fp_line
			(start -0.12065 0.3048)
			(end -0.67945 0.3048)
			(stroke
				(width 0.1)
				(type default)
			)
			(layer "F.Fab")
		)
		(fp_line
			(start 0.120396 0.3048)
			(end 0.120396 0.2794)
			(stroke
				(width 0.1)
				(type default)
			)
			(layer "F.Fab")
		)
		(fp_line
			(start 0.67945 0.3048)
			(end 0.120396 0.3048)
			(stroke
				(width 0.1)
				(type default)
			)
			(layer "F.Fab")
		)
		(fp_line
			(start -0.12065 0.2794)
			(end -0.12065 0.3048)
			(stroke
				(width 0.1)
				(type default)
			)
			(layer "F.Fab")
		)
		(fp_line
			(start 0.120396 0.2794)
			(end -0.12065 0.2794)
			(stroke
				(width 0.1)
				(type default)
			)
			(layer "F.Fab")
		)
		(fp_line
			(start -0.12065 -0.2794)
			(end 0.12065 -0.2794)
			(stroke
				(width 0.1)
				(type default)
			)
			(layer "F.Fab")
		)
		(fp_line
			(start 0.12065 -0.2794)
			(end 0.12065 -0.3048)
			(stroke
				(width 0.1)
				(type default)
			)
			(layer "F.Fab")
		)
		(fp_line
			(start 0.12065 -0.3048)
			(end 0.67945 -0.3048)
			(stroke
				(width 0.1)
				(type default)
			)
			(layer "F.Fab")
		)
		(fp_line
			(start 0.67945 -0.3048)
			(end 0.67945 0.3048)
			(stroke
				(width 0.1)
				(type default)
			)
			(layer "F.Fab")
		)
		(fp_line
			(start -0.67945 -0.305054)
			(end -0.12065 -0.305054)
			(stroke
				(width 0.1)
				(type default)
			)
			(layer "F.Fab")
		)
		(fp_line
			(start -0.12065 -0.305054)
			(end -0.12065 -0.2794)
			(stroke
				(width 0.1)
				(type default)
			)
			(layer "F.Fab")
		)
		(pad "1" smd circle
			(at -0.40005 0 270)
			(size 0 0)
			(layers "F.Cu" "F.Mask" "F.Paste")
			(net "P3V3_AUX")
		)
		(pad "2" smd circle
			(at 0.40005 0 270)
			(size 0 0)
			(layers "F.Cu" "F.Mask" "F.Paste")
			(net "P3V3_E1S_VCC_0")
		)
	)
	(footprint ""
		(layer "F.Cu")
		(at 437.242966 -125.696726 180)
		(property "Reference" "R2401"
			(at 0 0 180)
			(layer "F.SilkS")
			(hide yes)
			(effects
				(font
					(size 1.27 1.27)
				)
			)
		)
		(property "Value" ""
			(at 0 0 180)
			(layer "F.Fab")
			(effects
				(font
					(size 1.27 1.27)
				)
			)
		)
		(duplicate_pad_numbers_are_jumpers no)
		(fp_line
			(start 0.7874 0.4064)
			(end -0.7874 0.4064)
			(stroke
				(width 0.1524)
				(type default)
			)
			(layer "F.SilkS")
		)
		(fp_line
			(start 0.7874 -0.4064)
			(end 0.7874 0.4064)
			(stroke
				(width 0.1524)
				(type default)
			)
			(layer "F.SilkS")
		)
		(fp_line
			(start -0.7874 0.4064)
			(end -0.7874 -0.4064)
			(stroke
				(width 0.1524)
				(type default)
			)
			(layer "F.SilkS")
		)
		(fp_line
			(start -0.7874 -0.4064)
			(end 0.7874 -0.4064)
			(stroke
				(width 0.1524)
				(type default)
			)
			(layer "F.SilkS")
		)
		(fp_line
			(start 0.67945 0.3048)
			(end 0.120396 0.3048)
			(stroke
				(width 0.1)
				(type default)
			)
			(layer "F.Fab")
		)
		(fp_line
			(start 0.67945 -0.3048)
			(end 0.67945 0.3048)
			(stroke
				(width 0.1)
				(type default)
			)
			(layer "F.Fab")
		)
		(fp_line
			(start 0.12065 -0.2794)
			(end 0.12065 -0.3048)
			(stroke
				(width 0.1)
				(type default)
			)
			(layer "F.Fab")
		)
		(fp_line
			(start 0.12065 -0.3048)
			(end 0.67945 -0.3048)
			(stroke
				(width 0.1)
				(type default)
			)
			(layer "F.Fab")
		)
		(fp_line
			(start 0.120396 0.3048)
			(end 0.120396 0.2794)
			(stroke
				(width 0.1)
				(type default)
			)
			(layer "F.Fab")
		)
		(fp_line
			(start 0.120396 0.2794)
			(end -0.12065 0.2794)
			(stroke
				(width 0.1)
				(type default)
			)
			(layer "F.Fab")
		)
		(fp_line
			(start -0.12065 0.3048)
			(end -0.67945 0.3048)
			(stroke
				(width 0.1)
				(type default)
			)
			(layer "F.Fab")
		)
		(fp_line
			(start -0.12065 0.2794)
			(end -0.12065 0.3048)
			(stroke
				(width 0.1)
				(type default)
			)
			(layer "F.Fab")
		)
		(fp_line
			(start -0.12065 -0.2794)
			(end 0.12065 -0.2794)
			(stroke
				(width 0.1)
				(type default)
			)
			(layer "F.Fab")
		)
		(fp_line
			(start -0.12065 -0.305054)
			(end -0.12065 -0.2794)
			(stroke
				(width 0.1)
				(type default)
			)
			(layer "F.Fab")
		)
		(fp_line
			(start -0.67945 0.3048)
			(end -0.67945 -0.305054)
			(stroke
				(width 0.1)
				(type default)
			)
			(layer "F.Fab")
		)
		(fp_line
			(start -0.67945 -0.305054)
			(end -0.12065 -0.305054)
			(stroke
				(width 0.1)
				(type default)
			)
			(layer "F.Fab")
		)
		(pad "1" smd circle
			(at -0.40005 0 180)
			(size 0 0)
			(layers "F.Cu" "F.Mask" "F.Paste")
			(net "SVID_ALERT1_CPU0_R_N")
		)
		(pad "2" smd circle
			(at 0.40005 0 180)
			(size 0 0)
			(layers "F.Cu" "F.Mask" "F.Paste")
			(net "SVID_ALERT_PVCCD_HV_CPU0_R")
		)
	)
	(footprint ""
		(layer "F.Cu")
		(at 24.684482 -396.887192 -90)
		(property "Reference" "R4664"
			(at 0 0 270)
			(layer "F.SilkS")
			(hide yes)
			(effects
				(font
					(size 1.27 1.27)
				)
			)
		)
		(property "Value" ""
			(at 0 0 270)
			(layer "F.Fab")
			(effects
				(font
					(size 1.27 1.27)
				)
			)
		)
		(duplicate_pad_numbers_are_jumpers no)
		(fp_line
			(start -0.7874 0.4064)
			(end -0.7874 -0.4064)
			(stroke
				(width 0.1524)
				(type default)
			)
			(layer "F.SilkS")
		)
		(fp_line
			(start 0.7874 0.4064)
			(end -0.7874 0.4064)
			(stroke
				(width 0.1524)
				(type default)
			)
			(layer "F.SilkS")
		)
		(fp_line
			(start 0.017272 -0.4064)
			(end 0.7874 -0.4064)
			(stroke
				(width 0.1524)
				(type default)
			)
			(layer "F.SilkS")
		)
		(fp_line
			(start -0.67945 0.3048)
			(end -0.67945 -0.305054)
			(stroke
				(width 0.1)
				(type default)
			)
			(layer "F.Fab")
		)
		(fp_line
			(start -0.12065 0.3048)
			(end -0.67945 0.3048)
			(stroke
				(width 0.1)
				(type default)
			)
			(layer "F.Fab")
		)
		(fp_line
			(start 0.120396 0.3048)
			(end 0.120396 0.2794)
			(stroke
				(width 0.1)
				(type default)
			)
			(layer "F.Fab")
		)
		(fp_line
			(start 0.67945 0.3048)
			(end 0.120396 0.3048)
			(stroke
				(width 0.1)
				(type default)
			)
			(layer "F.Fab")
		)
		(fp_line
			(start -0.12065 0.2794)
			(end -0.12065 0.3048)
			(stroke
				(width 0.1)
				(type default)
			)
			(layer "F.Fab")
		)
		(fp_line
			(start 0.120396 0.2794)
			(end -0.12065 0.2794)
			(stroke
				(width 0.1)
				(type default)
			)
			(layer "F.Fab")
		)
		(fp_line
			(start -0.12065 -0.2794)
			(end 0.12065 -0.2794)
			(stroke
				(width 0.1)
				(type default)
			)
			(layer "F.Fab")
		)
		(fp_line
			(start 0.12065 -0.2794)
			(end 0.12065 -0.3048)
			(stroke
				(width 0.1)
				(type default)
			)
			(layer "F.Fab")
		)
		(fp_line
			(start 0.12065 -0.3048)
			(end 0.67945 -0.3048)
			(stroke
				(width 0.1)
				(type default)
			)
			(layer "F.Fab")
		)
		(fp_line
			(start 0.67945 -0.3048)
			(end 0.67945 0.3048)
			(stroke
				(width 0.1)
				(type default)
			)
			(layer "F.Fab")
		)
		(fp_line
			(start -0.67945 -0.305054)
			(end -0.12065 -0.305054)
			(stroke
				(width 0.1)
				(type default)
			)
			(layer "F.Fab")
		)
		(fp_line
			(start -0.12065 -0.305054)
			(end -0.12065 -0.2794)
			(stroke
				(width 0.1)
				(type default)
			)
			(layer "F.Fab")
		)
		(pad "1" smd rect
			(at -0.40005 0 90)
			(size 0.4572 0.508)
			(layers "F.Cu" "F.Mask" "F.Paste")
			(net "P2E_MB_BMC_RX_DN<0>")
		)
		(pad "2" smd rect
			(at 0.40005 0 90)
			(size 0.4572 0.508)
			(layers "F.Cu" "F.Mask" "F.Paste")
			(net "P2E_MB_BMC_RX_R1_DN<0>")
		)
	)
	(footprint ""
		(layer "F.Cu")
		(at 210.086956 -30.276292 90)
		(property "Reference" "R3622"
			(at 0 0 90)
			(layer "F.SilkS")
			(hide yes)
			(effects
				(font
					(size 1.27 1.27)
				)
			)
		)
		(property "Value" ""
			(at 0 0 90)
			(layer "F.Fab")
			(effects
				(font
					(size 1.27 1.27)
				)
			)
		)
		(duplicate_pad_numbers_are_jumpers no)
		(fp_line
			(start 0.7874 -0.4064)
			(end 0.7874 0.4064)
			(stroke
				(width 0.1524)
				(type default)
			)
			(layer "F.SilkS")
		)
		(fp_line
			(start -0.7874 -0.4064)
			(end 0.7874 -0.4064)
			(stroke
				(width 0.1524)
				(type default)
			)
			(layer "F.SilkS")
		)
		(fp_line
			(start 0.7874 0.4064)
			(end -0.7874 0.4064)
			(stroke
				(width 0.1524)
				(type default)
			)
			(layer "F.SilkS")
		)
		(fp_line
			(start -0.7874 0.4064)
			(end -0.7874 -0.4064)
			(stroke
				(width 0.1524)
				(type default)
			)
			(layer "F.SilkS")
		)
		(fp_line
			(start -0.12065 -0.305054)
			(end -0.12065 -0.2794)
			(stroke
				(width 0.1)
				(type default)
			)
			(layer "F.Fab")
		)
		(fp_line
			(start -0.67945 -0.305054)
			(end -0.12065 -0.305054)
			(stroke
				(width 0.1)
				(type default)
			)
			(layer "F.Fab")
		)
		(fp_line
			(start 0.67945 -0.3048)
			(end 0.67945 0.3048)
			(stroke
				(width 0.1)
				(type default)
			)
			(layer "F.Fab")
		)
		(fp_line
			(start 0.12065 -0.3048)
			(end 0.67945 -0.3048)
			(stroke
				(width 0.1)
				(type default)
			)
			(layer "F.Fab")
		)
		(fp_line
			(start 0.12065 -0.2794)
			(end 0.12065 -0.3048)
			(stroke
				(width 0.1)
				(type default)
			)
			(layer "F.Fab")
		)
		(fp_line
			(start -0.12065 -0.2794)
			(end 0.12065 -0.2794)
			(stroke
				(width 0.1)
				(type default)
			)
			(layer "F.Fab")
		)
		(fp_line
			(start 0.120396 0.2794)
			(end -0.12065 0.2794)
			(stroke
				(width 0.1)
				(type default)
			)
			(layer "F.Fab")
		)
		(fp_line
			(start -0.12065 0.2794)
			(end -0.12065 0.3048)
			(stroke
				(width 0.1)
				(type default)
			)
			(layer "F.Fab")
		)
		(fp_line
			(start 0.67945 0.3048)
			(end 0.120396 0.3048)
			(stroke
				(width 0.1)
				(type default)
			)
			(layer "F.Fab")
		)
		(fp_line
			(start 0.120396 0.3048)
			(end 0.120396 0.2794)
			(stroke
				(width 0.1)
				(type default)
			)
			(layer "F.Fab")
		)
		(fp_line
			(start -0.12065 0.3048)
			(end -0.67945 0.3048)
			(stroke
				(width 0.1)
				(type default)
			)
			(layer "F.Fab")
		)
		(fp_line
			(start -0.67945 0.3048)
			(end -0.67945 -0.305054)
			(stroke
				(width 0.1)
				(type default)
			)
			(layer "F.Fab")
		)
		(pad "1" smd circle
			(at -0.40005 0 90)
			(size 0 0)
			(layers "F.Cu" "F.Mask" "F.Paste")
			(net "P3V3_AUX")
		)
		(pad "2" smd circle
			(at 0.40005 0 90)
			(size 0 0)
			(layers "F.Cu" "F.Mask" "F.Paste")
			(net "INA230_5_A0")
		)
	)
	(footprint ""
		(layer "F.Cu")
		(at 246.784622 -90.651584 180)
		(property "Reference" "C2037"
			(at 0 0 180)
			(layer "F.SilkS")
			(hide yes)
			(effects
				(font
					(size 1.27 1.27)
				)
			)
		)
		(property "Value" ""
			(at 0 0 180)
			(layer "F.Fab")
			(effects
				(font
					(size 1.27 1.27)
				)
			)
		)
		(duplicate_pad_numbers_are_jumpers no)
		(fp_line
			(start 0.7874 0.4064)
			(end -0.7874 0.4064)
			(stroke
				(width 0.1524)
				(type default)
			)
			(layer "F.SilkS")
		)
		(fp_line
			(start 0.7874 -0.4064)
			(end 0.7874 0.4064)
			(stroke
				(width 0.1524)
				(type default)
			)
			(layer "F.SilkS")
		)
		(fp_line
			(start -0.7874 0.4064)
			(end -0.7874 -0.4064)
			(stroke
				(width 0.1524)
				(type default)
			)
			(layer "F.SilkS")
		)
		(fp_line
			(start -0.7874 -0.4064)
			(end 0.7874 -0.4064)
			(stroke
				(width 0.1524)
				(type default)
			)
			(layer "F.SilkS")
		)
		(fp_line
			(start 0.67945 0.3048)
			(end 0.120396 0.3048)
			(stroke
				(width 0.1)
				(type default)
			)
			(layer "F.Fab")
		)
		(fp_line
			(start 0.67945 -0.3048)
			(end 0.67945 0.3048)
			(stroke
				(width 0.1)
				(type default)
			)
			(layer "F.Fab")
		)
		(fp_line
			(start 0.12065 -0.2794)
			(end 0.12065 -0.3048)
			(stroke
				(width 0.1)
				(type default)
			)
			(layer "F.Fab")
		)
		(fp_line
			(start 0.12065 -0.3048)
			(end 0.67945 -0.3048)
			(stroke
				(width 0.1)
				(type default)
			)
			(layer "F.Fab")
		)
		(fp_line
			(start 0.120396 0.3048)
			(end 0.120396 0.2794)
			(stroke
				(width 0.1)
				(type default)
			)
			(layer "F.Fab")
		)
		(fp_line
			(start 0.120396 0.2794)
			(end -0.12065 0.2794)
			(stroke
				(width 0.1)
				(type default)
			)
			(layer "F.Fab")
		)
		(fp_line
			(start -0.12065 0.3048)
			(end -0.67945 0.3048)
			(stroke
				(width 0.1)
				(type default)
			)
			(layer "F.Fab")
		)
		(fp_line
			(start -0.12065 0.2794)
			(end -0.12065 0.3048)
			(stroke
				(width 0.1)
				(type default)
			)
			(layer "F.Fab")
		)
		(fp_line
			(start -0.12065 -0.2794)
			(end 0.12065 -0.2794)
			(stroke
				(width 0.1)
				(type default)
			)
			(layer "F.Fab")
		)
		(fp_line
			(start -0.12065 -0.305054)
			(end -0.12065 -0.2794)
			(stroke
				(width 0.1)
				(type default)
			)
			(layer "F.Fab")
		)
		(fp_line
			(start -0.67945 0.3048)
			(end -0.67945 -0.305054)
			(stroke
				(width 0.1)
				(type default)
			)
			(layer "F.Fab")
		)
		(fp_line
			(start -0.67945 -0.305054)
			(end -0.12065 -0.305054)
			(stroke
				(width 0.1)
				(type default)
			)
			(layer "F.Fab")
		)
		(pad "1" smd circle
			(at -0.40005 0 180)
			(size 0 0)
			(layers "F.Cu" "F.Mask" "F.Paste")
			(net "XTAL_CLK_GEN1_25M_X2")
		)
		(pad "2" smd circle
			(at 0.40005 0 180)
			(size 0 0)
			(layers "F.Cu" "F.Mask" "F.Paste")
			(net "GND")
		)
	)
	(footprint ""
		(layer "F.Cu")
		(at 104.361234 -247.715278 90)
		(property "Reference" "C425"
			(at 0 0 90)
			(layer "F.SilkS")
			(hide yes)
			(effects
				(font
					(size 1.27 1.27)
				)
			)
		)
		(property "Value" ""
			(at 0 0 90)
			(layer "F.Fab")
			(effects
				(font
					(size 1.27 1.27)
				)
			)
		)
		(duplicate_pad_numbers_are_jumpers no)
		(fp_line
			(start 0.7874 -0.4064)
			(end 0.7874 0.4064)
			(stroke
				(width 0.1524)
				(type default)
			)
			(layer "F.SilkS")
		)
		(fp_line
			(start -0.7874 -0.4064)
			(end 0.7874 -0.4064)
			(stroke
				(width 0.1524)
				(type default)
			)
			(layer "F.SilkS")
		)
		(fp_line
			(start 0.7874 0.4064)
			(end -0.7874 0.4064)
			(stroke
				(width 0.1524)
				(type default)
			)
			(layer "F.SilkS")
		)
		(fp_line
			(start -0.7874 0.4064)
			(end -0.7874 -0.4064)
			(stroke
				(width 0.1524)
				(type default)
			)
			(layer "F.SilkS")
		)
		(fp_line
			(start -0.12065 -0.305054)
			(end -0.12065 -0.2794)
			(stroke
				(width 0.1)
				(type default)
			)
			(layer "F.Fab")
		)
		(fp_line
			(start -0.67945 -0.305054)
			(end -0.12065 -0.305054)
			(stroke
				(width 0.1)
				(type default)
			)
			(layer "F.Fab")
		)
		(fp_line
			(start 0.67945 -0.3048)
			(end 0.67945 0.3048)
			(stroke
				(width 0.1)
				(type default)
			)
			(layer "F.Fab")
		)
		(fp_line
			(start 0.12065 -0.3048)
			(end 0.67945 -0.3048)
			(stroke
				(width 0.1)
				(type default)
			)
			(layer "F.Fab")
		)
		(fp_line
			(start 0.12065 -0.2794)
			(end 0.12065 -0.3048)
			(stroke
				(width 0.1)
				(type default)
			)
			(layer "F.Fab")
		)
		(fp_line
			(start -0.12065 -0.2794)
			(end 0.12065 -0.2794)
			(stroke
				(width 0.1)
				(type default)
			)
			(layer "F.Fab")
		)
		(fp_line
			(start 0.120396 0.2794)
			(end -0.12065 0.2794)
			(stroke
				(width 0.1)
				(type default)
			)
			(layer "F.Fab")
		)
		(fp_line
			(start -0.12065 0.2794)
			(end -0.12065 0.3048)
			(stroke
				(width 0.1)
				(type default)
			)
			(layer "F.Fab")
		)
		(fp_line
			(start 0.67945 0.3048)
			(end 0.120396 0.3048)
			(stroke
				(width 0.1)
				(type default)
			)
			(layer "F.Fab")
		)
		(fp_line
			(start 0.120396 0.3048)
			(end 0.120396 0.2794)
			(stroke
				(width 0.1)
				(type default)
			)
			(layer "F.Fab")
		)
		(fp_line
			(start -0.12065 0.3048)
			(end -0.67945 0.3048)
			(stroke
				(width 0.1)
				(type default)
			)
			(layer "F.Fab")
		)
		(fp_line
			(start -0.67945 0.3048)
			(end -0.67945 -0.305054)
			(stroke
				(width 0.1)
				(type default)
			)
			(layer "F.Fab")
		)
		(pad "1" smd circle
			(at -0.40005 0 90)
			(size 0 0)
			(layers "F.Cu" "F.Mask" "F.Paste")
			(net "PVCCD_HV_CPU1")
		)
		(pad "2" smd circle
			(at 0.40005 0 90)
			(size 0 0)
			(layers "F.Cu" "F.Mask" "F.Paste")
			(net "GND")
		)
	)
	(footprint ""
		(layer "F.Cu")
		(at 179.749958 -435.600094)
		(property "Reference" "H89"
			(at -5.998718 -4.288536 0)
			(unlocked yes)
			(layer "F.SilkS")
			(effects
				(font
					(size 0.7874 0.5842)
					(thickness 0.1524)
				)
				(justify left)
			)
		)
		(property "Value" ""
			(at 0 0 0)
			(layer "F.Fab")
			(effects
				(font
					(size 1.27 1.27)
				)
			)
		)
		(duplicate_pad_numbers_are_jumpers no)
		(pad "1" thru_hole circle
			(at 0 0)
			(size 10.0076 10.0076)
			(drill 5.6134)
			(layers "*.Cu" "*.Mask")
			(remove_unused_layers no)
			(net "GND")
			(clearance -1.9431)
		)
	)
)
